(kicad_pcb
	(version 20260206)
	(generator "pcbnew")
	(generator_version "10.0")
	(general
		(thickness 1.6)
		(legacy_teardrops no)
	)
	(paper "A4")
	(title_block
		(title "01162023_DA0F0TEBIF0_F0T_Expander_BD_F_brd_V02_OCP.brd")
		(comment 1 "Grand Teton / footprints 2969-2975 of 9728")
	)
	(layers
		(0 "F.Cu" signal "TOP")
		(4 "In1.Cu" signal "GND")
		(6 "In2.Cu" signal "VCC")
		(8 "In3.Cu" signal "VCC1")
		(10 "In4.Cu" signal "GND1")
		(12 "In5.Cu" signal "IN1")
		(14 "In6.Cu" signal "GND2")
		(16 "In7.Cu" signal "IN2")
		(18 "In8.Cu" signal "GND3")
		(20 "In9.Cu" signal "IN3")
		(22 "In10.Cu" signal "GND4")
		(24 "In11.Cu" signal "IN4")
		(26 "In12.Cu" signal "GND5")
		(28 "In13.Cu" signal "IN5")
		(30 "In14.Cu" signal "GND6")
		(32 "In15.Cu" signal "IN6")
		(34 "In16.Cu" signal "GND7")
		(2 "B.Cu" signal "BOTTOM")
		(9 "F.Adhes" user "F.Adhesive")
		(11 "B.Adhes" user "B.Adhesive")
		(13 "F.Paste" user "Package Geometry/Pastemask Top")
		(15 "B.Paste" user "Package Geometry/Pastemask Bottom")
		(5 "F.SilkS" user "Ref Des/Silkscreen Top")
		(7 "B.SilkS" user "Ref Des/Silkscreen Bottom")
		(1 "F.Mask" user "Board Geometry/Soldermask Top")
		(3 "B.Mask" user "Board Geometry/Soldermask Bottom")
		(17 "Dwgs.User" user "User.Drawings")
		(19 "Cmts.User" user "User.Comments")
		(21 "Eco1.User" user "User.Eco1")
		(23 "Eco2.User" user "User.Eco2")
		(25 "Edge.Cuts" user "Board Geometry/Outline")
		(27 "Margin" user)
		(31 "F.CrtYd" user "Package Geometry/Place Bound Top")
		(29 "B.CrtYd" user "Package Geometry/Place Bound Bottom")
		(35 "F.Fab" user "Ref Des/Assembly Top")
		(33 "B.Fab" user "Ref Des/Assembly Bottom")
	)
	(footprint ""
		(layer "F.Cu")
		(at 319.937892 -291.102034 180)
		(property "Reference" "R6395"
			(at 0 0 180)
			(layer "F.SilkS")
			(hide yes)
			(effects
				(font
					(size 1.27 1.27)
				)
			)
		)
		(property "Value" ""
			(at 0 0 180)
			(layer "F.Fab")
			(effects
				(font
					(size 1.27 1.27)
				)
			)
		)
		(duplicate_pad_numbers_are_jumpers no)
		(fp_line
			(start 0.7874 0.4064)
			(end -0.7874 0.4064)
			(stroke
				(width 0.1524)
				(type default)
			)
			(layer "F.SilkS")
		)
		(fp_line
			(start 0.7874 -0.4064)
			(end 0.7874 0.4064)
			(stroke
				(width 0.1524)
				(type default)
			)
			(layer "F.SilkS")
		)
		(fp_line
			(start -0.7874 0.4064)
			(end -0.7874 -0.4064)
			(stroke
				(width 0.1524)
				(type default)
			)
			(layer "F.SilkS")
		)
		(fp_line
			(start -0.7874 -0.4064)
			(end 0.7874 -0.4064)
			(stroke
				(width 0.1524)
				(type default)
			)
			(layer "F.SilkS")
		)
		(fp_line
			(start 0.67945 0.3048)
			(end 0.120396 0.3048)
			(stroke
				(width 0.1)
				(type default)
			)
			(layer "F.Fab")
		)
		(fp_line
			(start 0.67945 -0.3048)
			(end 0.67945 0.3048)
			(stroke
				(width 0.1)
				(type default)
			)
			(layer "F.Fab")
		)
		(fp_line
			(start 0.12065 -0.2794)
			(end 0.12065 -0.3048)
			(stroke
				(width 0.1)
				(type default)
			)
			(layer "F.Fab")
		)
		(fp_line
			(start 0.12065 -0.3048)
			(end 0.67945 -0.3048)
			(stroke
				(width 0.1)
				(type default)
			)
			(layer "F.Fab")
		)
		(fp_line
			(start 0.120396 0.3048)
			(end 0.120396 0.2794)
			(stroke
				(width 0.1)
				(type default)
			)
			(layer "F.Fab")
		)
		(fp_line
			(start 0.120396 0.2794)
			(end -0.12065 0.2794)
			(stroke
				(width 0.1)
				(type default)
			)
			(layer "F.Fab")
		)
		(fp_line
			(start -0.12065 0.3048)
			(end -0.67945 0.3048)
			(stroke
				(width 0.1)
				(type default)
			)
			(layer "F.Fab")
		)
		(fp_line
			(start -0.12065 0.2794)
			(end -0.12065 0.3048)
			(stroke
				(width 0.1)
				(type default)
			)
			(layer "F.Fab")
		)
		(fp_line
			(start -0.12065 -0.2794)
			(end 0.12065 -0.2794)
			(stroke
				(width 0.1)
				(type default)
			)
			(layer "F.Fab")
		)
		(fp_line
			(start -0.12065 -0.305054)
			(end -0.12065 -0.2794)
			(stroke
				(width 0.1)
				(type default)
			)
			(layer "F.Fab")
		)
		(fp_line
			(start -0.67945 0.3048)
			(end -0.67945 -0.305054)
			(stroke
				(width 0.1)
				(type default)
			)
			(layer "F.Fab")
		)
		(fp_line
			(start -0.67945 -0.305054)
			(end -0.12065 -0.305054)
			(stroke
				(width 0.1)
				(type default)
			)
			(layer "F.Fab")
		)
		(pad "1" smd circle
			(at -0.40005 0 180)
			(size 0 0)
			(layers "F.Cu" "F.Mask" "F.Paste")
			(net "GND")
		)
		(pad "2" smd circle
			(at 0.40005 0 180)
			(size 0 0)
			(layers "F.Cu" "F.Mask" "F.Paste")
			(net "RST_PEX2_PERST_R_N")
		)
	)
	(footprint ""
		(layer "F.Cu")
		(at 265.335512 -308.13375 -135)
		(property "Reference" "R1332"
			(at 0 0 225)
			(layer "F.SilkS")
			(hide yes)
			(effects
				(font
					(size 1.27 1.27)
				)
			)
		)
		(property "Value" ""
			(at 0 0 225)
			(layer "F.Fab")
			(effects
				(font
					(size 1.27 1.27)
				)
			)
		)
		(duplicate_pad_numbers_are_jumpers no)
		(fp_line
			(start 0.787389 0.406267)
			(end -0.787389 0.406267)
			(stroke
				(width 0.1524)
				(type default)
			)
			(layer "F.SilkS")
		)
		(fp_line
			(start 0.787389 -0.406267)
			(end 0.787389 0.406267)
			(stroke
				(width 0.1524)
				(type default)
			)
			(layer "F.SilkS")
		)
		(fp_line
			(start -0.787389 0.406267)
			(end -0.787389 -0.406267)
			(stroke
				(width 0.1524)
				(type default)
			)
			(layer "F.SilkS")
		)
		(fp_line
			(start -0.787389 -0.406267)
			(end 0.787389 -0.406267)
			(stroke
				(width 0.1524)
				(type default)
			)
			(layer "F.SilkS")
		)
		(fp_line
			(start 0.679446 0.30479)
			(end 0.120515 0.30479)
			(stroke
				(width 0.1)
				(type default)
			)
			(layer "F.Fab")
		)
		(fp_line
			(start 0.120515 0.30479)
			(end 0.120335 0.279466)
			(stroke
				(width 0.1)
				(type default)
			)
			(layer "F.Fab")
		)
		(fp_line
			(start 0.120335 0.279466)
			(end -0.120695 0.279466)
			(stroke
				(width 0.1)
				(type default)
			)
			(layer "F.Fab")
		)
		(fp_line
			(start 0.679446 -0.30479)
			(end 0.679446 0.30479)
			(stroke
				(width 0.1)
				(type default)
			)
			(layer "F.Fab")
		)
		(fp_line
			(start -0.120515 0.30479)
			(end -0.679446 0.30479)
			(stroke
				(width 0.1)
				(type default)
			)
			(layer "F.Fab")
		)
		(fp_line
			(start -0.120695 0.279466)
			(end -0.120515 0.30479)
			(stroke
				(width 0.1)
				(type default)
			)
			(layer "F.Fab")
		)
		(fp_line
			(start 0.120695 -0.279466)
			(end 0.120515 -0.30479)
			(stroke
				(width 0.1)
				(type default)
			)
			(layer "F.Fab")
		)
		(fp_line
			(start 0.120515 -0.30479)
			(end 0.679446 -0.30479)
			(stroke
				(width 0.1)
				(type default)
			)
			(layer "F.Fab")
		)
		(fp_line
			(start -0.679446 0.30479)
			(end -0.679446 -0.305149)
			(stroke
				(width 0.1)
				(type default)
			)
			(layer "F.Fab")
		)
		(fp_line
			(start -0.120695 -0.279466)
			(end 0.120695 -0.279466)
			(stroke
				(width 0.1)
				(type default)
			)
			(layer "F.Fab")
		)
		(fp_line
			(start -0.120695 -0.304969)
			(end -0.120695 -0.279466)
			(stroke
				(width 0.1)
				(type default)
			)
			(layer "F.Fab")
		)
		(fp_line
			(start -0.679446 -0.305149)
			(end -0.120695 -0.304969)
			(stroke
				(width 0.1)
				(type default)
			)
			(layer "F.Fab")
		)
		(pad "1" smd circle
			(at -0.40005 0 225)
			(size 0 0)
			(layers "F.Cu" "F.Mask" "F.Paste")
			(net "PEX2_DBG_MODE1")
		)
		(pad "2" smd circle
			(at 0.40005 0 225)
			(size 0 0)
			(layers "F.Cu" "F.Mask" "F.Paste")
			(net "P1V8_PEX")
		)
	)
	(footprint ""
		(layer "F.Cu")
		(at 377.3805 -350.098614 90)
		(property "Reference" "C784"
			(at 0 0 90)
			(layer "F.SilkS")
			(hide yes)
			(effects
				(font
					(size 1.27 1.27)
				)
			)
		)
		(property "Value" ""
			(at 0 0 90)
			(layer "F.Fab")
			(effects
				(font
					(size 1.27 1.27)
				)
			)
		)
		(duplicate_pad_numbers_are_jumpers no)
		(fp_line
			(start 0.299974 -0.150114)
			(end 0.299974 0.150114)
			(stroke
				(width 0.1)
				(type default)
			)
			(layer "F.Fab")
		)
		(fp_line
			(start -0.299974 -0.150114)
			(end 0.299974 -0.150114)
			(stroke
				(width 0.1)
				(type default)
			)
			(layer "F.Fab")
		)
		(fp_line
			(start 0.299974 0.150114)
			(end -0.299974 0.150114)
			(stroke
				(width 0.1)
				(type default)
			)
			(layer "F.Fab")
		)
		(fp_line
			(start -0.299974 0.150114)
			(end -0.299974 -0.150114)
			(stroke
				(width 0.1)
				(type default)
			)
			(layer "F.Fab")
		)
		(pad "1" smd rect
			(at -0.2667 0 90)
			(size 0.3048 0.381)
			(layers "F.Cu" "F.Mask" "F.Paste")
			(net "P5E_PEX3_STN6_TX_DP<100>")
		)
		(pad "2" smd rect
			(at 0.2667 0 90)
			(size 0.3048 0.381)
			(layers "F.Cu" "F.Mask" "F.Paste")
			(net "P5E_PEX3_STN6_TX_C_DP<100>")
		)
	)
	(footprint ""
		(layer "F.Cu")
		(at 203.92009 -289.230816 -90)
		(property "Reference" "R3934"
			(at 0 0 270)
			(layer "F.SilkS")
			(hide yes)
			(effects
				(font
					(size 1.27 1.27)
				)
			)
		)
		(property "Value" ""
			(at 0 0 270)
			(layer "F.Fab")
			(effects
				(font
					(size 1.27 1.27)
				)
			)
		)
		(duplicate_pad_numbers_are_jumpers no)
		(fp_line
			(start -0.7874 0.4064)
			(end -0.7874 -0.4064)
			(stroke
				(width 0.1524)
				(type default)
			)
			(layer "F.SilkS")
		)
		(fp_line
			(start 0.7874 0.4064)
			(end -0.7874 0.4064)
			(stroke
				(width 0.1524)
				(type default)
			)
			(layer "F.SilkS")
		)
		(fp_line
			(start -0.7874 -0.4064)
			(end 0.7874 -0.4064)
			(stroke
				(width 0.1524)
				(type default)
			)
			(layer "F.SilkS")
		)
		(fp_line
			(start 0.7874 -0.4064)
			(end 0.7874 0.4064)
			(stroke
				(width 0.1524)
				(type default)
			)
			(layer "F.SilkS")
		)
		(fp_line
			(start -0.67945 0.3048)
			(end -0.67945 -0.305054)
			(stroke
				(width 0.1)
				(type default)
			)
			(layer "F.Fab")
		)
		(fp_line
			(start -0.12065 0.3048)
			(end -0.67945 0.3048)
			(stroke
				(width 0.1)
				(type default)
			)
			(layer "F.Fab")
		)
		(fp_line
			(start 0.120396 0.3048)
			(end 0.120396 0.2794)
			(stroke
				(width 0.1)
				(type default)
			)
			(layer "F.Fab")
		)
		(fp_line
			(start 0.67945 0.3048)
			(end 0.120396 0.3048)
			(stroke
				(width 0.1)
				(type default)
			)
			(layer "F.Fab")
		)
		(fp_line
			(start -0.12065 0.2794)
			(end -0.12065 0.3048)
			(stroke
				(width 0.1)
				(type default)
			)
			(layer "F.Fab")
		)
		(fp_line
			(start 0.120396 0.2794)
			(end -0.12065 0.2794)
			(stroke
				(width 0.1)
				(type default)
			)
			(layer "F.Fab")
		)
		(fp_line
			(start -0.12065 -0.2794)
			(end 0.12065 -0.2794)
			(stroke
				(width 0.1)
				(type default)
			)
			(layer "F.Fab")
		)
		(fp_line
			(start 0.12065 -0.2794)
			(end 0.12065 -0.3048)
			(stroke
				(width 0.1)
				(type default)
			)
			(layer "F.Fab")
		)
		(fp_line
			(start 0.12065 -0.3048)
			(end 0.67945 -0.3048)
			(stroke
				(width 0.1)
				(type default)
			)
			(layer "F.Fab")
		)
		(fp_line
			(start 0.67945 -0.3048)
			(end 0.67945 0.3048)
			(stroke
				(width 0.1)
				(type default)
			)
			(layer "F.Fab")
		)
		(fp_line
			(start -0.67945 -0.305054)
			(end -0.12065 -0.305054)
			(stroke
				(width 0.1)
				(type default)
			)
			(layer "F.Fab")
		)
		(fp_line
			(start -0.12065 -0.305054)
			(end -0.12065 -0.2794)
			(stroke
				(width 0.1)
				(type default)
			)
			(layer "F.Fab")
		)
		(pad "1" smd circle
			(at -0.40005 0 270)
			(size 0 0)
			(layers "F.Cu" "F.Mask" "F.Paste")
			(net "SMB_PEX1_HOST_LS_SDA")
		)
		(pad "2" smd circle
			(at 0.40005 0 270)
			(size 0 0)
			(layers "F.Cu" "F.Mask" "F.Paste")
			(net "P3V3_AUX")
		)
	)
	(footprint ""
		(layer "F.Cu")
		(at 344.511884 -113.563654)
		(property "Reference" "PC816"
			(at 0 0 0)
			(layer "F.SilkS")
			(hide yes)
			(effects
				(font
					(size 1.27 1.27)
				)
			)
		)
		(property "Value" ""
			(at 0 0 0)
			(layer "F.Fab")
			(effects
				(font
					(size 1.27 1.27)
				)
			)
		)
		(duplicate_pad_numbers_are_jumpers no)
		(fp_line
			(start -0.7874 -0.4064)
			(end 0.7874 -0.4064)
			(stroke
				(width 0.1524)
				(type default)
			)
			(layer "F.SilkS")
		)
		(fp_line
			(start -0.7874 0.4064)
			(end -0.7874 -0.4064)
			(stroke
				(width 0.1524)
				(type default)
			)
			(layer "F.SilkS")
		)
		(fp_line
			(start 0.7874 -0.4064)
			(end 0.7874 0.4064)
			(stroke
				(width 0.1524)
				(type default)
			)
			(layer "F.SilkS")
		)
		(fp_line
			(start 0.7874 0.4064)
			(end -0.7874 0.4064)
			(stroke
				(width 0.1524)
				(type default)
			)
			(layer "F.SilkS")
		)
		(fp_line
			(start -0.67945 -0.305054)
			(end -0.12065 -0.305054)
			(stroke
				(width 0.1)
				(type default)
			)
			(layer "F.Fab")
		)
		(fp_line
			(start -0.67945 0.3048)
			(end -0.67945 -0.305054)
			(stroke
				(width 0.1)
				(type default)
			)
			(layer "F.Fab")
		)
		(fp_line
			(start -0.12065 -0.305054)
			(end -0.12065 -0.2794)
			(stroke
				(width 0.1)
				(type default)
			)
			(layer "F.Fab")
		)
		(fp_line
			(start -0.12065 -0.2794)
			(end 0.12065 -0.2794)
			(stroke
				(width 0.1)
				(type default)
			)
			(layer "F.Fab")
		)
		(fp_line
			(start -0.12065 0.2794)
			(end -0.12065 0.3048)
			(stroke
				(width 0.1)
				(type default)
			)
			(layer "F.Fab")
		)
		(fp_line
			(start -0.12065 0.3048)
			(end -0.67945 0.3048)
			(stroke
				(width 0.1)
				(type default)
			)
			(layer "F.Fab")
		)
		(fp_line
			(start 0.120396 0.2794)
			(end -0.12065 0.2794)
			(stroke
				(width 0.1)
				(type default)
			)
			(layer "F.Fab")
		)
		(fp_line
			(start 0.120396 0.3048)
			(end 0.120396 0.2794)
			(stroke
				(width 0.1)
				(type default)
			)
			(layer "F.Fab")
		)
		(fp_line
			(start 0.12065 -0.3048)
			(end 0.67945 -0.3048)
			(stroke
				(width 0.1)
				(type default)
			)
			(layer "F.Fab")
		)
		(fp_line
			(start 0.12065 -0.2794)
			(end 0.12065 -0.3048)
			(stroke
				(width 0.1)
				(type default)
			)
			(layer "F.Fab")
		)
		(fp_line
			(start 0.67945 -0.3048)
			(end 0.67945 0.3048)
			(stroke
				(width 0.1)
				(type default)
			)
			(layer "F.Fab")
		)
		(fp_line
			(start 0.67945 0.3048)
			(end 0.120396 0.3048)
			(stroke
				(width 0.1)
				(type default)
			)
			(layer "F.Fab")
		)
		(pad "1" smd circle
			(at -0.40005 0)
			(size 0 0)
			(layers "F.Cu" "F.Mask" "F.Paste")
			(net "P12V_NIC5_CO_SS")
		)
		(pad "2" smd circle
			(at 0.40005 0)
			(size 0 0)
			(layers "F.Cu" "F.Mask" "F.Paste")
			(net "GND")
		)
	)
	(footprint ""
		(layer "F.Cu")
		(at 352.12909 -205.156816 -90)
		(property "Reference" "R5778"
			(at 0 0 270)
			(layer "F.SilkS")
			(hide yes)
			(effects
				(font
					(size 1.27 1.27)
				)
			)
		)
		(property "Value" ""
			(at 0 0 270)
			(layer "F.Fab")
			(effects
				(font
					(size 1.27 1.27)
				)
			)
		)
		(duplicate_pad_numbers_are_jumpers no)
		(fp_line
			(start -0.7874 0.4064)
			(end -0.7874 -0.4064)
			(stroke
				(width 0.1524)
				(type default)
			)
			(layer "F.SilkS")
		)
		(fp_line
			(start 0.7874 0.4064)
			(end -0.7874 0.4064)
			(stroke
				(width 0.1524)
				(type default)
			)
			(layer "F.SilkS")
		)
		(fp_line
			(start -0.7874 -0.4064)
			(end 0.7874 -0.4064)
			(stroke
				(width 0.1524)
				(type default)
			)
			(layer "F.SilkS")
		)
		(fp_line
			(start 0.7874 -0.4064)
			(end 0.7874 0.4064)
			(stroke
				(width 0.1524)
				(type default)
			)
			(layer "F.SilkS")
		)
		(fp_line
			(start -0.67945 0.3048)
			(end -0.67945 -0.305054)
			(stroke
				(width 0.1)
				(type default)
			)
			(layer "F.Fab")
		)
		(fp_line
			(start -0.12065 0.3048)
			(end -0.67945 0.3048)
			(stroke
				(width 0.1)
				(type default)
			)
			(layer "F.Fab")
		)
		(fp_line
			(start 0.120396 0.3048)
			(end 0.120396 0.2794)
			(stroke
				(width 0.1)
				(type default)
			)
			(layer "F.Fab")
		)
		(fp_line
			(start 0.67945 0.3048)
			(end 0.120396 0.3048)
			(stroke
				(width 0.1)
				(type default)
			)
			(layer "F.Fab")
		)
		(fp_line
			(start -0.12065 0.2794)
			(end -0.12065 0.3048)
			(stroke
				(width 0.1)
				(type default)
			)
			(layer "F.Fab")
		)
		(fp_line
			(start 0.120396 0.2794)
			(end -0.12065 0.2794)
			(stroke
				(width 0.1)
				(type default)
			)
			(layer "F.Fab")
		)
		(fp_line
			(start -0.12065 -0.2794)
			(end 0.12065 -0.2794)
			(stroke
				(width 0.1)
				(type default)
			)
			(layer "F.Fab")
		)
		(fp_line
			(start 0.12065 -0.2794)
			(end 0.12065 -0.3048)
			(stroke
				(width 0.1)
				(type default)
			)
			(layer "F.Fab")
		)
		(fp_line
			(start 0.12065 -0.3048)
			(end 0.67945 -0.3048)
			(stroke
				(width 0.1)
				(type default)
			)
			(layer "F.Fab")
		)
		(fp_line
			(start 0.67945 -0.3048)
			(end 0.67945 0.3048)
			(stroke
				(width 0.1)
				(type default)
			)
			(layer "F.Fab")
		)
		(fp_line
			(start -0.67945 -0.305054)
			(end -0.12065 -0.305054)
			(stroke
				(width 0.1)
				(type default)
			)
			(layer "F.Fab")
		)
		(fp_line
			(start -0.12065 -0.305054)
			(end -0.12065 -0.2794)
			(stroke
				(width 0.1)
				(type default)
			)
			(layer "F.Fab")
		)
		(pad "1" smd circle
			(at -0.40005 0 270)
			(size 0 0)
			(layers "F.Cu" "F.Mask" "F.Paste")
			(net "FM_PFR_LED_AMBER")
		)
		(pad "2" smd circle
			(at 0.40005 0 270)
			(size 0 0)
			(layers "F.Cu" "F.Mask" "F.Paste")
			(net "FM_PFR_LED_AMBER_R")
		)
	)
	(footprint ""
		(layer "F.Cu")
		(at 198.62673 -53.697124 -90)
		(property "Reference" "PC496"
			(at 0 0 270)
			(layer "F.SilkS")
			(hide yes)
			(effects
				(font
					(size 1.27 1.27)
				)
			)
		)
		(property "Value" ""
			(at 0 0 270)
			(layer "F.Fab")
			(effects
				(font
					(size 1.27 1.27)
				)
			)
		)
		(duplicate_pad_numbers_are_jumpers no)
		(fp_line
			(start -0.7874 0.4064)
			(end -0.7874 -0.4064)
			(stroke
				(width 0.1524)
				(type default)
			)
			(layer "F.SilkS")
		)
		(fp_line
			(start 0.7874 0.4064)
			(end -0.7874 0.4064)
			(stroke
				(width 0.1524)
				(type default)
			)
			(layer "F.SilkS")
		)
		(fp_line
			(start -0.7874 -0.4064)
			(end 0.7874 -0.4064)
			(stroke
				(width 0.1524)
				(type default)
			)
			(layer "F.SilkS")
		)
		(fp_line
			(start 0.7874 -0.4064)
			(end 0.7874 0.4064)
			(stroke
				(width 0.1524)
				(type default)
			)
			(layer "F.SilkS")
		)
		(fp_line
			(start -0.67945 0.3048)
			(end -0.67945 -0.305054)
			(stroke
				(width 0.1)
				(type default)
			)
			(layer "F.Fab")
		)
		(fp_line
			(start -0.12065 0.3048)
			(end -0.67945 0.3048)
			(stroke
				(width 0.1)
				(type default)
			)
			(layer "F.Fab")
		)
		(fp_line
			(start 0.120396 0.3048)
			(end 0.120396 0.2794)
			(stroke
				(width 0.1)
				(type default)
			)
			(layer "F.Fab")
		)
		(fp_line
			(start 0.67945 0.3048)
			(end 0.120396 0.3048)
			(stroke
				(width 0.1)
				(type default)
			)
			(layer "F.Fab")
		)
		(fp_line
			(start -0.12065 0.2794)
			(end -0.12065 0.3048)
			(stroke
				(width 0.1)
				(type default)
			)
			(layer "F.Fab")
		)
		(fp_line
			(start 0.120396 0.2794)
			(end -0.12065 0.2794)
			(stroke
				(width 0.1)
				(type default)
			)
			(layer "F.Fab")
		)
		(fp_line
			(start -0.12065 -0.2794)
			(end 0.12065 -0.2794)
			(stroke
				(width 0.1)
				(type default)
			)
			(layer "F.Fab")
		)
		(fp_line
			(start 0.12065 -0.2794)
			(end 0.12065 -0.3048)
			(stroke
				(width 0.1)
				(type default)
			)
			(layer "F.Fab")
		)
		(fp_line
			(start 0.12065 -0.3048)
			(end 0.67945 -0.3048)
			(stroke
				(width 0.1)
				(type default)
			)
			(layer "F.Fab")
		)
		(fp_line
			(start 0.67945 -0.3048)
			(end 0.67945 0.3048)
			(stroke
				(width 0.1)
				(type default)
			)
			(layer "F.Fab")
		)
		(fp_line
			(start -0.67945 -0.305054)
			(end -0.12065 -0.305054)
			(stroke
				(width 0.1)
				(type default)
			)
			(layer "F.Fab")
		)
		(fp_line
			(start -0.12065 -0.305054)
			(end -0.12065 -0.2794)
			(stroke
				(width 0.1)
				(type default)
			)
			(layer "F.Fab")
		)
		(pad "1" smd circle
			(at -0.40005 0 270)
			(size 0 0)
			(layers "F.Cu" "F.Mask" "F.Paste")
			(net "P3V3_AUX")
		)
		(pad "2" smd circle
			(at 0.40005 0 270)
			(size 0 0)
			(layers "F.Cu" "F.Mask" "F.Paste")
			(net "GND")
		)
	)
)
